(kicad_pcb
	(version 20260206)
	(generator "pcbnew")
	(generator_version "10.0")
	(general
		(thickness 1.6)
		(legacy_teardrops no)
	)
	(paper "A4")
	(title_block
		(title "baseboard — 13948-1b.1110WZS1818.brd")
		(comment 1 "Honey Badger (Wiwynn) / footprints 2384-2392 of 2523")
	)
	(layers
		(0 "F.Cu" signal "TOP")
		(4 "In1.Cu" signal "L2GND")
		(6 "In2.Cu" signal "L3")
		(8 "In3.Cu" signal "L4VCC")
		(10 "In4.Cu" signal "L5VCC")
		(12 "In5.Cu" signal "L6")
		(14 "In6.Cu" signal "L7GND")
		(2 "B.Cu" signal "BOTTOM")
		(9 "F.Adhes" user "F.Adhesive")
		(11 "B.Adhes" user "B.Adhesive")
		(13 "F.Paste" user "Package Geometry/Pastemask Top")
		(15 "B.Paste" user "Package Geometry/Pastemask Bottom")
		(5 "F.SilkS" user "Ref Des/Silkscreen Top")
		(7 "B.SilkS" user "Ref Des/Silkscreen Bottom")
		(1 "F.Mask" user "Board Geometry/Soldermask Top")
		(3 "B.Mask" user "Board Geometry/Soldermask Bottom")
		(17 "Dwgs.User" user "User.Drawings")
		(19 "Cmts.User" user "User.Comments")
		(21 "Eco1.User" user "User.Eco1")
		(23 "Eco2.User" user "User.Eco2")
		(25 "Edge.Cuts" user "Board Geometry/Outline")
		(27 "Margin" user)
		(31 "F.CrtYd" user "Package Geometry/Place Bound Top")
		(29 "B.CrtYd" user "Package Geometry/Place Bound Bottom")
		(35 "F.Fab" user "Ref Des/Assembly Top")
		(33 "B.Fab" user "Ref Des/Assembly Bottom")
	)
	(footprint ""
		(layer "B.Cu")
		(at 303.26584 -181.1655)
		(property "Reference" "TP161"
			(at 0 0 0)
			(layer "B.SilkS")
			(hide yes)
			(effects
				(font
					(size 1.27 1.27)
				)
				(justify mirror)
			)
		)
		(property "Value" "TPAD28"
			(at -0.0127 -1.8034 0)
			(unlocked yes)
			(layer "B.Fab")
			(hide yes)
			(effects
				(font
					(size 1.016 1.016)
					(thickness 0.1524)
				)
				(justify mirror)
			)
		)
		(property "Device Type" "TPAD28"
			(at -0.0127 -3.3274 0)
			(unlocked yes)
			(layer "B.Fab")
			(hide yes)
			(effects
				(font
					(size 1.016 1.016)
					(thickness 0.1524)
				)
				(justify mirror)
			)
		)
		(duplicate_pad_numbers_are_jumpers no)
		(fp_poly
			(pts
				(arc
					(start 0.3556 0)
					(mid -0.3556 0)
					(end 0.3556 0)
				)
			)
			(stroke
				(width 0)
				(type default)
			)
			(fill no)
			(layer "B.CrtYd")
		)
		(fp_poly
			(pts
				(arc
					(start 0.6096 0)
					(mid -0.6096 0)
					(end 0.6096 0)
				)
			)
			(stroke
				(width 0)
				(type default)
			)
			(fill no)
			(layer "B.Fab")
		)
		(pad "1" smd circle
			(at 0 0 180)
			(size 0.7112 0.7112)
			(layers "B.Cu" "B.Mask" "B.Paste")
			(net "TP_BMC_GPIOJ6")
		)
	)
	(footprint ""
		(layer "B.Cu")
		(at 290.01466 -169.45102)
		(property "Reference" "TP141"
			(at 0 0 0)
			(layer "B.SilkS")
			(hide yes)
			(effects
				(font
					(size 1.27 1.27)
				)
				(justify mirror)
			)
		)
		(property "Value" "TPAD28"
			(at -0.0127 -1.8034 0)
			(unlocked yes)
			(layer "B.Fab")
			(hide yes)
			(effects
				(font
					(size 1.016 1.016)
					(thickness 0.1524)
				)
				(justify mirror)
			)
		)
		(property "Device Type" "TPAD28"
			(at -0.0127 -3.3274 0)
			(unlocked yes)
			(layer "B.Fab")
			(hide yes)
			(effects
				(font
					(size 1.016 1.016)
					(thickness 0.1524)
				)
				(justify mirror)
			)
		)
		(duplicate_pad_numbers_are_jumpers no)
		(fp_poly
			(pts
				(arc
					(start 0.3556 0)
					(mid -0.3556 0)
					(end 0.3556 0)
				)
			)
			(stroke
				(width 0)
				(type default)
			)
			(fill no)
			(layer "B.CrtYd")
		)
		(fp_poly
			(pts
				(arc
					(start 0.6096 0)
					(mid -0.6096 0)
					(end 0.6096 0)
				)
			)
			(stroke
				(width 0)
				(type default)
			)
			(fill no)
			(layer "B.Fab")
		)
		(pad "1" smd circle
			(at 0 0 180)
			(size 0.7112 0.7112)
			(layers "B.Cu" "B.Mask" "B.Paste")
			(net "TP_BMC_GPIOE4")
		)
	)
	(footprint ""
		(layer "B.Cu")
		(at 104.02316 -31.623)
		(property "Reference" "SC875"
			(at 0 0 0)
			(layer "B.SilkS")
			(hide yes)
			(effects
				(font
					(size 1.27 1.27)
				)
				(justify mirror)
			)
		)
		(property "Value" "SCD22U6D3V1MX-1-GP"
			(at 2.8321 -1.7399 0)
			(unlocked yes)
			(layer "B.Fab")
			(hide yes)
			(effects
				(font
					(size 1.016 1.016)
					(thickness 0.1524)
				)
				(justify mirror)
			)
		)
		(property "Device Type" "C0201H13"
			(at 2.8321 -3.2639 0)
			(unlocked yes)
			(layer "B.Fab")
			(hide yes)
			(effects
				(font
					(size 1.016 1.016)
					(thickness 0.1524)
				)
				(justify mirror)
			)
		)
		(duplicate_pad_numbers_are_jumpers no)
		(fp_rect
			(start 0.2794 0.6477)
			(end -0.2794 -0.6477)
			(stroke
				(width 0)
				(type default)
			)
			(fill no)
			(layer "B.CrtYd")
		)
		(fp_rect
			(start 0.2794 0.6477)
			(end -0.2794 -0.6477)
			(stroke
				(width 0)
				(type default)
			)
			(fill no)
			(layer "B.Fab")
		)
		(pad "1" smd custom
			(at 0 -0.2794 180)
			(size 0.0762 0.0762)
			(layers "B.Cu" "B.Mask" "B.Paste")
			(net "PCIE_SAS_C_CPU_RX_P7")
			(options
				(clearance outline)
				(anchor circle)
			)
			(primitives
				(gr_poly
					(pts
						(arc
							(start 0.1524 0.127)
							(mid 0.137521 0.162921)
							(end 0.1016 0.1778)
						)
						(arc
							(start -0.1016 0.1778)
							(mid -0.137521 0.162921)
							(end -0.1524 0.127)
						)
						(arc
							(start -0.1524 -0.127)
							(mid -0.137521 -0.162921)
							(end -0.1016 -0.1778)
						)
						(arc
							(start 0.1016 -0.1778)
							(mid 0.137521 -0.162921)
							(end 0.1524 -0.127)
						)
					)
					(width 0)
					(fill yes)
				)
			)
		)
		(pad "2" smd custom
			(at 0 0.2794 180)
			(size 0.0762 0.0762)
			(layers "B.Cu" "B.Mask" "B.Paste")
			(net "PCIE_SAS_CPU_RX_P7")
			(options
				(clearance outline)
				(anchor circle)
			)
			(primitives
				(gr_poly
					(pts
						(arc
							(start 0.1524 0.127)
							(mid 0.137521 0.162921)
							(end 0.1016 0.1778)
						)
						(arc
							(start -0.1016 0.1778)
							(mid -0.137521 0.162921)
							(end -0.1524 0.127)
						)
						(arc
							(start -0.1524 -0.127)
							(mid -0.137521 -0.162921)
							(end -0.1016 -0.1778)
						)
						(arc
							(start 0.1016 -0.1778)
							(mid 0.137521 -0.162921)
							(end 0.1524 -0.127)
						)
					)
					(width 0)
					(fill yes)
				)
			)
		)
	)
	(footprint ""
		(layer "B.Cu")
		(at 319.913 -167.894 90)
		(property "Reference" "R437"
			(at 0 0 90)
			(layer "B.SilkS")
			(hide yes)
			(effects
				(font
					(size 1.27 1.27)
				)
				(justify mirror)
			)
		)
		(property "Value" "4K7R2F-GP"
			(at -0.064008 -3.993896 90)
			(unlocked yes)
			(layer "B.Fab")
			(hide yes)
			(effects
				(font
					(size 1.016 1.016)
					(thickness 0.1524)
				)
				(justify mirror)
			)
		)
		(property "Device Type" "R402H16"
			(at -0.064008 -5.517896 90)
			(unlocked yes)
			(layer "B.Fab")
			(hide yes)
			(effects
				(font
					(size 1.016 1.016)
					(thickness 0.1524)
				)
				(justify mirror)
			)
		)
		(duplicate_pad_numbers_are_jumpers no)
		(fp_line
			(start 0.508 -0.9398)
			(end 0.508 0.9398)
			(stroke
				(width 0.1524)
				(type default)
			)
			(layer "B.SilkS")
		)
		(fp_line
			(start -0.508 -0.9398)
			(end 0.508 -0.9398)
			(stroke
				(width 0.1524)
				(type default)
			)
			(layer "B.SilkS")
		)
		(fp_rect
			(start 0.508 0.9398)
			(end -0.508 -0.9398)
			(stroke
				(width 0)
				(type default)
			)
			(fill no)
			(layer "B.CrtYd")
		)
		(fp_rect
			(start 0.508 0.9398)
			(end -0.508 -0.9398)
			(stroke
				(width 0)
				(type default)
			)
			(fill no)
			(layer "B.Fab")
		)
		(pad "1" smd custom
			(at 0 -0.4445 270)
			(size 0.1397 0.1397)
			(layers "B.Cu" "B.Mask" "B.Paste")
			(net "BMC_I2C_A_SCL")
			(options
				(clearance outline)
				(anchor circle)
			)
			(primitives
				(gr_poly
					(pts
						(arc
							(start -0.1778 0.2794)
							(mid -0.249642 0.249642)
							(end -0.2794 0.1778)
						)
						(arc
							(start -0.2794 -0.1778)
							(mid -0.249642 -0.249642)
							(end -0.1778 -0.2794)
						)
						(arc
							(start 0.1778 -0.2794)
							(mid 0.249642 -0.249642)
							(end 0.2794 -0.1778)
						)
						(arc
							(start 0.2794 0.1778)
							(mid 0.249642 0.249642)
							(end 0.1778 0.2794)
						)
					)
					(width 0)
					(fill yes)
				)
			)
		)
		(pad "2" smd custom
			(at 0 0.4445 270)
			(size 0.1397 0.1397)
			(layers "B.Cu" "B.Mask" "B.Paste")
			(net "P3V3_STBY")
			(options
				(clearance outline)
				(anchor circle)
			)
			(primitives
				(gr_poly
					(pts
						(arc
							(start -0.1778 0.2794)
							(mid -0.249642 0.249642)
							(end -0.2794 0.1778)
						)
						(arc
							(start -0.2794 -0.1778)
							(mid -0.249642 -0.249642)
							(end -0.1778 -0.2794)
						)
						(arc
							(start 0.1778 -0.2794)
							(mid 0.249642 -0.249642)
							(end 0.2794 -0.1778)
						)
						(arc
							(start 0.2794 0.1778)
							(mid 0.249642 0.249642)
							(end 0.1778 0.2794)
						)
					)
					(width 0)
					(fill yes)
				)
			)
		)
	)
	(footprint ""
		(layer "B.Cu")
		(at 110.587282 -37.008054 -90)
		(property "Reference" "SR669"
			(at 0 0 90)
			(layer "B.SilkS")
			(hide yes)
			(effects
				(font
					(size 1.27 1.27)
				)
				(justify mirror)
			)
		)
		(property "Value" "10KR2F-2-GP"
			(at -0.064008 -3.993896 270)
			(unlocked yes)
			(layer "B.Fab")
			(hide yes)
			(effects
				(font
					(size 1.016 1.016)
					(thickness 0.1524)
				)
				(justify mirror)
			)
		)
		(property "Device Type" "R402H16"
			(at -0.064008 -5.517896 270)
			(unlocked yes)
			(layer "B.Fab")
			(hide yes)
			(effects
				(font
					(size 1.016 1.016)
					(thickness 0.1524)
				)
				(justify mirror)
			)
		)
		(duplicate_pad_numbers_are_jumpers no)
		(fp_line
			(start -0.508 -0.9398)
			(end 0.508 -0.9398)
			(stroke
				(width 0.1524)
				(type default)
			)
			(layer "B.SilkS")
		)
		(fp_line
			(start 0.508 -0.9398)
			(end 0.508 0.9398)
			(stroke
				(width 0.1524)
				(type default)
			)
			(layer "B.SilkS")
		)
		(fp_rect
			(start 0.508 0.9398)
			(end -0.508 -0.9398)
			(stroke
				(width 0)
				(type default)
			)
			(fill no)
			(layer "B.CrtYd")
		)
		(fp_rect
			(start 0.508 0.9398)
			(end -0.508 -0.9398)
			(stroke
				(width 0)
				(type default)
			)
			(fill no)
			(layer "B.Fab")
		)
		(pad "1" smd custom
			(at 0 -0.4445 90)
			(size 0.1397 0.1397)
			(layers "B.Cu" "B.Mask" "B.Paste")
			(net "P1V8_C")
			(options
				(clearance outline)
				(anchor circle)
			)
			(primitives
				(gr_poly
					(pts
						(arc
							(start -0.1778 0.2794)
							(mid -0.249642 0.249642)
							(end -0.2794 0.1778)
						)
						(arc
							(start -0.2794 -0.1778)
							(mid -0.249642 -0.249642)
							(end -0.1778 -0.2794)
						)
						(arc
							(start 0.1778 -0.2794)
							(mid 0.249642 -0.249642)
							(end 0.2794 -0.1778)
						)
						(arc
							(start 0.2794 0.1778)
							(mid 0.249642 0.249642)
							(end 0.1778 0.2794)
						)
					)
					(width 0)
					(fill yes)
				)
			)
		)
		(pad "2" smd custom
			(at 0 0.4445 90)
			(size 0.1397 0.1397)
			(layers "B.Cu" "B.Mask" "B.Paste")
			(net "SYS_RST_N_1")
			(options
				(clearance outline)
				(anchor circle)
			)
			(primitives
				(gr_poly
					(pts
						(arc
							(start -0.1778 0.2794)
							(mid -0.249642 0.249642)
							(end -0.2794 0.1778)
						)
						(arc
							(start -0.2794 -0.1778)
							(mid -0.249642 -0.249642)
							(end -0.1778 -0.2794)
						)
						(arc
							(start 0.1778 -0.2794)
							(mid 0.249642 -0.249642)
							(end 0.2794 -0.1778)
						)
						(arc
							(start 0.2794 0.1778)
							(mid 0.249642 0.249642)
							(end 0.1778 0.2794)
						)
					)
					(width 0)
					(fill yes)
				)
			)
		)
	)
	(footprint ""
		(layer "B.Cu")
		(at 295.148 -164.211 180)
		(property "Reference" "R288"
			(at 0 0 0)
			(layer "B.SilkS")
			(hide yes)
			(effects
				(font
					(size 1.27 1.27)
				)
				(justify mirror)
			)
		)
		(property "Value" "47KR2F-GP"
			(at -0.064008 -3.993896 180)
			(unlocked yes)
			(layer "B.Fab")
			(hide yes)
			(effects
				(font
					(size 1.016 1.016)
					(thickness 0.1524)
				)
				(justify mirror)
			)
		)
		(property "Device Type" "R402H16"
			(at -0.064008 -5.517896 180)
			(unlocked yes)
			(layer "B.Fab")
			(hide yes)
			(effects
				(font
					(size 1.016 1.016)
					(thickness 0.1524)
				)
				(justify mirror)
			)
		)
		(duplicate_pad_numbers_are_jumpers no)
		(fp_line
			(start 0.508 -0.9398)
			(end 0.508 0.9398)
			(stroke
				(width 0.1524)
				(type default)
			)
			(layer "B.SilkS")
		)
		(fp_line
			(start -0.508 -0.9398)
			(end 0.508 -0.9398)
			(stroke
				(width 0.1524)
				(type default)
			)
			(layer "B.SilkS")
		)
		(fp_rect
			(start 0.508 0.9398)
			(end -0.508 -0.9398)
			(stroke
				(width 0)
				(type default)
			)
			(fill no)
			(layer "B.CrtYd")
		)
		(fp_rect
			(start 0.508 0.9398)
			(end -0.508 -0.9398)
			(stroke
				(width 0)
				(type default)
			)
			(fill no)
			(layer "B.Fab")
		)
		(pad "1" smd custom
			(at 0 -0.4445)
			(size 0.1397 0.1397)
			(layers "B.Cu" "B.Mask" "B.Paste")
			(net "GND")
			(options
				(clearance outline)
				(anchor circle)
			)
			(primitives
				(gr_poly
					(pts
						(arc
							(start -0.1778 0.2794)
							(mid -0.249642 0.249642)
							(end -0.2794 0.1778)
						)
						(arc
							(start -0.2794 -0.1778)
							(mid -0.249642 -0.249642)
							(end -0.1778 -0.2794)
						)
						(arc
							(start 0.1778 -0.2794)
							(mid 0.249642 -0.249642)
							(end 0.2794 -0.1778)
						)
						(arc
							(start 0.2794 0.1778)
							(mid 0.249642 0.249642)
							(end 0.1778 0.2794)
						)
					)
					(width 0)
					(fill yes)
				)
			)
		)
		(pad "2" smd custom
			(at 0 0.4445)
			(size 0.1397 0.1397)
			(layers "B.Cu" "B.Mask" "B.Paste")
			(net "RMII0_BMC_C_RX_ER")
			(options
				(clearance outline)
				(anchor circle)
			)
			(primitives
				(gr_poly
					(pts
						(arc
							(start -0.1778 0.2794)
							(mid -0.249642 0.249642)
							(end -0.2794 0.1778)
						)
						(arc
							(start -0.2794 -0.1778)
							(mid -0.249642 -0.249642)
							(end -0.1778 -0.2794)
						)
						(arc
							(start 0.1778 -0.2794)
							(mid 0.249642 -0.249642)
							(end 0.2794 -0.1778)
						)
						(arc
							(start 0.2794 0.1778)
							(mid 0.249642 0.249642)
							(end 0.1778 0.2794)
						)
					)
					(width 0)
					(fill yes)
				)
			)
		)
	)
	(footprint ""
		(layer "B.Cu")
		(at 124.85497 -94.361 90)
		(property "Reference" "SC1166"
			(at 0 0 90)
			(layer "B.SilkS")
			(hide yes)
			(effects
				(font
					(size 1.27 1.27)
				)
				(justify mirror)
			)
		)
		(property "Value" "SC1U6D3V1MX-GP"
			(at -1.9177 2.0193 90)
			(unlocked yes)
			(layer "B.Fab")
			(hide yes)
			(effects
				(font
					(size 1.016 1.016)
					(thickness 0.1524)
				)
				(justify mirror)
			)
		)
		(property "Device Type" "C0201H14"
			(at -1.9177 0.4953 90)
			(unlocked yes)
			(layer "B.Fab")
			(hide yes)
			(effects
				(font
					(size 1.016 1.016)
					(thickness 0.1524)
				)
				(justify mirror)
			)
		)
		(duplicate_pad_numbers_are_jumpers no)
		(fp_rect
			(start 0.1524 0.3048)
			(end -0.1524 -0.3048)
			(stroke
				(width 0)
				(type default)
			)
			(fill no)
			(layer "B.CrtYd")
		)
		(fp_poly
			(pts
				(xy 0.2794 0.6477) (xy 0.2794 -0.6477) (xy -0.2794 -0.6477) (xy -0.2794 -0.1905) (xy -0.1524 -0.1905)
				(xy -0.1524 -0.3048) (xy 0.1524 -0.3048) (xy 0.1524 0.3048) (xy -0.1524 0.3048) (xy -0.1524 -0.1778)
				(xy -0.2794 -0.1778) (xy -0.2794 0.6477)
			)
			(stroke
				(width 0)
				(type default)
			)
			(fill no)
			(layer "B.CrtYd")
		)
		(fp_rect
			(start 0.2794 0.6477)
			(end -0.2794 -0.6477)
			(stroke
				(width 0)
				(type default)
			)
			(fill no)
			(layer "B.Fab")
		)
		(pad "1" smd custom
			(at 0 -0.2794 270)
			(size 0.0762 0.0762)
			(layers "B.Cu" "B.Mask" "B.Paste")
			(net "GB_VDDA")
			(options
				(clearance outline)
				(anchor circle)
			)
			(primitives
				(gr_poly
					(pts
						(arc
							(start 0.1524 0.127)
							(mid 0.137521 0.162921)
							(end 0.1016 0.1778)
						)
						(arc
							(start -0.1016 0.1778)
							(mid -0.137521 0.162921)
							(end -0.1524 0.127)
						)
						(arc
							(start -0.1524 -0.127)
							(mid -0.137521 -0.162921)
							(end -0.1016 -0.1778)
						)
						(arc
							(start 0.1016 -0.1778)
							(mid 0.137521 -0.162921)
							(end 0.1524 -0.127)
						)
					)
					(width 0)
					(fill yes)
				)
			)
		)
		(pad "2" smd custom
			(at 0 0.2794 270)
			(size 0.0762 0.0762)
			(layers "B.Cu" "B.Mask" "B.Paste")
			(net "GND")
			(options
				(clearance outline)
				(anchor circle)
			)
			(primitives
				(gr_poly
					(pts
						(arc
							(start 0.1524 0.127)
							(mid 0.137521 0.162921)
							(end 0.1016 0.1778)
						)
						(arc
							(start -0.1016 0.1778)
							(mid -0.137521 0.162921)
							(end -0.1524 0.127)
						)
						(arc
							(start -0.1524 -0.127)
							(mid -0.137521 -0.162921)
							(end -0.1016 -0.1778)
						)
						(arc
							(start 0.1016 -0.1778)
							(mid 0.137521 -0.162921)
							(end 0.1524 -0.127)
						)
					)
					(width 0)
					(fill yes)
				)
			)
		)
	)
	(footprint ""
		(layer "B.Cu")
		(at 114.36477 -35.625532)
		(property "Reference" "STP4"
			(at 0 0 0)
			(layer "B.SilkS")
			(hide yes)
			(effects
				(font
					(size 1.27 1.27)
				)
				(justify mirror)
			)
		)
		(property "Value" "TPAD28"
			(at -0.0127 -1.8034 0)
			(unlocked yes)
			(layer "B.Fab")
			(hide yes)
			(effects
				(font
					(size 1.016 1.016)
					(thickness 0.1524)
				)
				(justify mirror)
			)
		)
		(property "Device Type" "TPAD28"
			(at -0.0127 -3.3274 0)
			(unlocked yes)
			(layer "B.Fab")
			(hide yes)
			(effects
				(font
					(size 1.016 1.016)
					(thickness 0.1524)
				)
				(justify mirror)
			)
		)
		(duplicate_pad_numbers_are_jumpers no)
		(fp_poly
			(pts
				(arc
					(start 0.3556 0)
					(mid -0.3556 0)
					(end 0.3556 0)
				)
			)
			(stroke
				(width 0)
				(type default)
			)
			(fill no)
			(layer "B.CrtYd")
		)
		(fp_poly
			(pts
				(arc
					(start 0.6096 0)
					(mid -0.6096 0)
					(end 0.6096 0)
				)
			)
			(stroke
				(width 0)
				(type default)
			)
			(fill no)
			(layer "B.Fab")
		)
		(pad "1" smd circle
			(at 0 0 180)
			(size 0.7112 0.7112)
			(layers "B.Cu" "B.Mask" "B.Paste")
			(net "IOC_GPIO_26")
		)
	)
	(footprint ""
		(layer "B.Cu")
		(at 274.193 -180.721 90)
		(property "Reference" "R349"
			(at 0 0 90)
			(layer "B.SilkS")
			(hide yes)
			(effects
				(font
					(size 1.27 1.27)
				)
				(justify mirror)
			)
		)
		(property "Value" "3K3R2F-2-GP"
			(at -0.064008 -3.993896 90)
			(unlocked yes)
			(layer "B.Fab")
			(hide yes)
			(effects
				(font
					(size 1.016 1.016)
					(thickness 0.1524)
				)
				(justify mirror)
			)
		)
		(property "Device Type" "R402H16"
			(at -0.064008 -5.517896 90)
			(unlocked yes)
			(layer "B.Fab")
			(hide yes)
			(effects
				(font
					(size 1.016 1.016)
					(thickness 0.1524)
				)
				(justify mirror)
			)
		)
		(duplicate_pad_numbers_are_jumpers no)
		(fp_line
			(start 0.508 -0.9398)
			(end 0.508 0.9398)
			(stroke
				(width 0.1524)
				(type default)
			)
			(layer "B.SilkS")
		)
		(fp_line
			(start -0.508 -0.9398)
			(end 0.508 -0.9398)
			(stroke
				(width 0.1524)
				(type default)
			)
			(layer "B.SilkS")
		)
		(fp_rect
			(start 0.508 0.9398)
			(end -0.508 -0.9398)
			(stroke
				(width 0)
				(type default)
			)
			(fill no)
			(layer "B.CrtYd")
		)
		(fp_rect
			(start 0.508 0.9398)
			(end -0.508 -0.9398)
			(stroke
				(width 0)
				(type default)
			)
			(fill no)
			(layer "B.Fab")
		)
		(pad "1" smd custom
			(at 0 -0.4445 270)
			(size 0.1397 0.1397)
			(layers "B.Cu" "B.Mask" "B.Paste")
			(net "P3V3_STBY")
			(options
				(clearance outline)
				(anchor circle)
			)
			(primitives
				(gr_poly
					(pts
						(arc
							(start -0.1778 0.2794)
							(mid -0.249642 0.249642)
							(end -0.2794 0.1778)
						)
						(arc
							(start -0.2794 -0.1778)
							(mid -0.249642 -0.249642)
							(end -0.1778 -0.2794)
						)
						(arc
							(start 0.1778 -0.2794)
							(mid 0.249642 -0.249642)
							(end 0.2794 -0.1778)
						)
						(arc
							(start 0.2794 0.1778)
							(mid 0.249642 0.249642)
							(end 0.1778 0.2794)
						)
					)
					(width 0)
					(fill yes)
				)
			)
		)
		(pad "2" smd custom
			(at 0 0.4445 270)
			(size 0.1397 0.1397)
			(layers "B.Cu" "B.Mask" "B.Paste")
			(net "ROMA18")
			(options
				(clearance outline)
				(anchor circle)
			)
			(primitives
				(gr_poly
					(pts
						(arc
							(start -0.1778 0.2794)
							(mid -0.249642 0.249642)
							(end -0.2794 0.1778)
						)
						(arc
							(start -0.2794 -0.1778)
							(mid -0.249642 -0.249642)
							(end -0.1778 -0.2794)
						)
						(arc
							(start 0.1778 -0.2794)
							(mid 0.249642 -0.249642)
							(end 0.2794 -0.1778)
						)
						(arc
							(start 0.2794 0.1778)
							(mid 0.249642 0.249642)
							(end 0.1778 0.2794)
						)
					)
					(width 0)
					(fill yes)
				)
			)
		)
	)
)
